(kicad_pcb
	(version 20260206)
	(generator "pcbnew")
	(generator_version "10.0")
	(general
		(thickness 1.6)
		(legacy_teardrops no)
	)
	(paper "A4")
	(title_block
		(title "Wiwynn_Tioga_Pass_MB.brd")
		(comment 1 "Tioga Pass / footprints 349-350 of 4770")
	)
	(layers
		(0 "F.Cu" signal "TOP")
		(4 "In1.Cu" signal "L2GND")
		(6 "In2.Cu" signal "L3")
		(8 "In3.Cu" signal "L4GND")
		(10 "In4.Cu" signal "L5")
		(12 "In5.Cu" signal "L6GND")
		(14 "In6.Cu" signal "L7VCC")
		(16 "In7.Cu" signal "L8VCC")
		(18 "In8.Cu" signal "L9GND")
		(20 "In9.Cu" signal "L10")
		(22 "In10.Cu" signal "L11GND")
		(24 "In11.Cu" signal "L12")
		(26 "In12.Cu" signal "L13GND")
		(2 "B.Cu" signal "BOTTOM")
		(9 "F.Adhes" user "F.Adhesive")
		(11 "B.Adhes" user "B.Adhesive")
		(13 "F.Paste" user "Package Geometry/Pastemask Top")
		(15 "B.Paste" user "Package Geometry/Pastemask Bottom")
		(5 "F.SilkS" user "Ref Des/Silkscreen Top")
		(7 "B.SilkS" user "Ref Des/Silkscreen Bottom")
		(1 "F.Mask" user "Board Geometry/Soldermask Top")
		(3 "B.Mask" user "Board Geometry/Soldermask Bottom")
		(17 "Dwgs.User" user "User.Drawings")
		(19 "Cmts.User" user "User.Comments")
		(21 "Eco1.User" user "User.Eco1")
		(23 "Eco2.User" user "User.Eco2")
		(25 "Edge.Cuts" user "Board Geometry/Outline")
		(27 "Margin" user)
		(31 "F.CrtYd" user "Package Geometry/Place Bound Top")
		(29 "B.CrtYd" user "Package Geometry/Place Bound Bottom")
		(35 "F.Fab" user "Ref Des/Assembly Top")
		(33 "B.Fab" user "Ref Des/Assembly Bottom")
	)
	(footprint ""
		(layer "F.Cu")
		(at 440.550046 -57.596024 90)
		(property "Reference" "J8E4"
			(at 1.795272 -4.825746 90)
			(unlocked yes)
			(layer "F.SilkS")
			(effects
				(font
					(size 0.7874 0.5842)
					(thickness 0.1524)
				)
			)
		)
		(property "Value" ""
			(at 0 0 90)
			(layer "F.Fab")
			(effects
				(font
					(size 1.27 1.27)
				)
			)
		)
		(duplicate_pad_numbers_are_jumpers no)
		(fp_line
			(start 5.678424 -3.374898)
			(end 5.678424 -0.5842)
			(stroke
				(width 0.1524)
				(type default)
			)
			(layer "F.SilkS")
		)
		(fp_line
			(start 3.168396 -3.374898)
			(end 5.678424 -3.374898)
			(stroke
				(width 0.1524)
				(type default)
			)
			(layer "F.SilkS")
		)
		(fp_line
			(start -1.271778 -3.374898)
			(end 1.237996 -3.374898)
			(stroke
				(width 0.1524)
				(type default)
			)
			(layer "F.SilkS")
		)
		(fp_line
			(start -1.271778 -0.5842)
			(end -1.271778 -3.374898)
			(stroke
				(width 0.1524)
				(type default)
			)
			(layer "F.SilkS")
		)
		(fp_line
			(start -1.271778 25.384252)
			(end -1.271778 28.17495)
			(stroke
				(width 0.1524)
				(type default)
			)
			(layer "F.SilkS")
		)
		(fp_line
			(start 5.678424 28.17495)
			(end 5.678424 25.384252)
			(stroke
				(width 0.1524)
				(type default)
			)
			(layer "F.SilkS")
		)
		(fp_line
			(start 3.168396 28.17495)
			(end 5.678424 28.17495)
			(stroke
				(width 0.1524)
				(type default)
			)
			(layer "F.SilkS")
		)
		(fp_line
			(start -1.271778 28.17495)
			(end 1.237996 28.17495)
			(stroke
				(width 0.1524)
				(type default)
			)
			(layer "F.SilkS")
		)
		(fp_poly
			(pts
				(xy -2.986024 -0.4953) (xy -2.986024 0.5207) (xy -1.716024 0.0127)
			)
			(stroke
				(width 0)
				(type default)
			)
			(fill yes)
			(layer "F.SilkS")
		)
		(fp_poly
			(pts
				(xy -1.271778 -3.374898) (xy -1.271778 28.17495) (xy 5.678424 28.17495) (xy 5.678424 -3.374898)
			)
			(stroke
				(width 0)
				(type default)
			)
			(fill no)
			(layer "F.CrtYd")
		)
		(fp_line
			(start 5.678424 -3.374898)
			(end 5.678424 28.17495)
			(stroke
				(width 0.1)
				(type default)
			)
			(layer "F.Fab")
		)
		(fp_line
			(start -1.271778 -3.374898)
			(end 5.678424 -3.374898)
			(stroke
				(width 0.1)
				(type default)
			)
			(layer "F.Fab")
		)
		(fp_line
			(start 5.678424 28.17495)
			(end -1.271778 28.17495)
			(stroke
				(width 0.1)
				(type default)
			)
			(layer "F.Fab")
		)
		(fp_line
			(start -1.271778 28.17495)
			(end -1.271778 -3.374898)
			(stroke
				(width 0.1)
				(type default)
			)
			(layer "F.Fab")
		)
		(fp_poly
			(pts
				(xy -2.986024 -0.4953) (xy -2.986024 0.5207) (xy -1.716024 0.0127)
			)
			(stroke
				(width 0)
				(type default)
			)
			(fill yes)
			(layer "F.Fab")
		)
		(fp_text user "33"
			(at 6.764782 -1.348994 0)
			(unlocked yes)
			(layer "F.SilkS")
			(effects
				(font
					(size 0.7874 0.5842)
					(thickness 0.1524)
				)
				(justify left)
			)
		)
		(fp_text user "32"
			(at -2.003298 24.851106 0)
			(unlocked yes)
			(layer "F.SilkS")
			(effects
				(font
					(size 0.7874 0.5842)
					(thickness 0.1524)
				)
				(justify left)
			)
		)
		(fp_text user "64"
			(at 6.415786 25.105106 0)
			(unlocked yes)
			(layer "F.SilkS")
			(effects
				(font
					(size 0.7874 0.5842)
					(thickness 0.1524)
				)
				(justify left)
			)
		)
		(fp_text user "33"
			(at 6.76529 -1.350264 0)
			(unlocked yes)
			(layer "F.Fab")
			(effects
				(font
					(size 0.7874 0.5842)
					(thickness 0.1524)
				)
				(justify left)
			)
		)
		(fp_text user "32"
			(at -2.00279 24.847296 0)
			(unlocked yes)
			(layer "F.Fab")
			(effects
				(font
					(size 0.7874 0.5842)
					(thickness 0.1524)
				)
				(justify left)
			)
		)
		(fp_text user "64"
			(at 6.41604 25.103836 0)
			(unlocked yes)
			(layer "F.Fab")
			(effects
				(font
					(size 0.7874 0.5842)
					(thickness 0.1524)
				)
				(justify left)
			)
		)
		(pad "" np_thru_hole circle
			(at 2.203196 -2.500122 90)
			(size 0.254 0.254)
			(drill 1.1938)
			(layers "*.Cu" "*.Mask")
			(clearance 0.7874)
			(thermal_gap 0.7874)
		)
		(pad "" np_thru_hole circle
			(at 2.203196 27.29992 90)
			(size 0.254 0.254)
			(drill 0.8128)
			(layers "*.Cu" "*.Mask")
			(clearance 0.5969)
			(thermal_gap 0.5969)
		)
		(pad "1" smd rect
			(at 0 0 90)
			(size 2.0066 0.508)
			(layers "F.Cu" "F.Mask" "F.Paste")
			(net "SMB_OCP_FRU_STBY_LVC3_SCL")
		)
		(pad "2" smd rect
			(at 0 0.8001 90)
			(size 2.0066 0.508)
			(layers "F.Cu" "F.Mask" "F.Paste")
			(net "SMB_OCP_FRU_STBY_LVC3_SDA")
		)
		(pad "3" smd rect
			(at 0 1.599946 90)
			(size 2.0066 0.508)
			(layers "F.Cu" "F.Mask" "F.Paste")
			(net "EXT_MDIO_I2C_SEL")
		)
		(pad "4" smd rect
			(at 0 2.400046 90)
			(size 2.0066 0.508)
			(layers "F.Cu" "F.Mask" "F.Paste")
			(net "GND")
		)
		(pad "5" smd rect
			(at 0 3.199892 90)
			(size 2.0066 0.508)
			(layers "F.Cu" "F.Mask" "F.Paste")
			(net "Net_446")
		)
		(pad "6" smd rect
			(at 0 3.999992 90)
			(size 2.0066 0.508)
			(layers "F.Cu" "F.Mask" "F.Paste")
			(net "Net_445")
		)
		(pad "7" smd rect
			(at 0 4.800092 90)
			(size 2.0066 0.508)
			(layers "F.Cu" "F.Mask" "F.Paste")
			(net "GND")
		)
		(pad "8" smd rect
			(at 0 5.599938 90)
			(size 2.0066 0.508)
			(layers "F.Cu" "F.Mask" "F.Paste")
			(net "LED_GBE_P1_0")
		)
		(pad "9" smd rect
			(at 0 6.400038 90)
			(size 2.0066 0.508)
			(layers "F.Cu" "F.Mask" "F.Paste")
			(net "LED_GBE_P1_1")
		)
		(pad "10" smd rect
			(at 0 7.199884 90)
			(size 2.0066 0.508)
			(layers "F.Cu" "F.Mask" "F.Paste")
			(net "GND")
		)
		(pad "11" smd rect
			(at 0 7.999984 90)
			(size 2.0066 0.508)
			(layers "F.Cu" "F.Mask" "F.Paste")
			(net "Net_450")
		)
		(pad "12" smd rect
			(at 0 8.800084 90)
			(size 2.0066 0.508)
			(layers "F.Cu" "F.Mask" "F.Paste")
			(net "Net_449")
		)
		(pad "13" smd rect
			(at 0 9.59993 90)
			(size 2.0066 0.508)
			(layers "F.Cu" "F.Mask" "F.Paste")
			(net "GND")
		)
		(pad "14" smd rect
			(at 0 10.40003 90)
			(size 2.0066 0.508)
			(layers "F.Cu" "F.Mask" "F.Paste")
			(net "LED_GBE_P2_0")
		)
		(pad "15" smd rect
			(at 0 11.199876 90)
			(size 2.0066 0.508)
			(layers "F.Cu" "F.Mask" "F.Paste")
			(net "LED_GBE_P2_1")
		)
		(pad "16" smd rect
			(at 0 11.999976 90)
			(size 2.0066 0.508)
			(layers "F.Cu" "F.Mask" "F.Paste")
			(net "GND")
		)
		(pad "17" smd rect
			(at 0 12.800076 90)
			(size 2.0066 0.508)
			(layers "F.Cu" "F.Mask" "F.Paste")
			(net "Net_444")
		)
		(pad "18" smd rect
			(at 0 13.599922 90)
			(size 2.0066 0.508)
			(layers "F.Cu" "F.Mask" "F.Paste")
			(net "Net_443")
		)
		(pad "19" smd rect
			(at 0 14.400022 90)
			(size 2.0066 0.508)
			(layers "F.Cu" "F.Mask" "F.Paste")
			(net "GND")
		)
		(pad "20" smd rect
			(at 0 15.200122 90)
			(size 2.0066 0.508)
			(layers "F.Cu" "F.Mask" "F.Paste")
			(net "SMB_PCH_MEZZ_LOM0_SCL")
		)
		(pad "21" smd rect
			(at 0 15.999968 90)
			(size 2.0066 0.508)
			(layers "F.Cu" "F.Mask" "F.Paste")
			(net "SMB_PCH_MEZZ_LOM0_SDA")
		)
		(pad "22" smd rect
			(at 0 16.800068 90)
			(size 2.0066 0.508)
			(layers "F.Cu" "F.Mask" "F.Paste")
			(net "GND")
		)
		(pad "23" smd rect
			(at 0 17.599914 90)
			(size 2.0066 0.508)
			(layers "F.Cu" "F.Mask" "F.Paste")
			(net "Net_448")
		)
		(pad "24" smd rect
			(at 0 18.400014 90)
			(size 2.0066 0.508)
			(layers "F.Cu" "F.Mask" "F.Paste")
			(net "Net_447")
		)
		(pad "25" smd rect
			(at 0 19.200114 90)
			(size 2.0066 0.508)
			(layers "F.Cu" "F.Mask" "F.Paste")
			(net "GND")
		)
		(pad "26" smd rect
			(at 0 19.99996 90)
			(size 2.0066 0.508)
			(layers "F.Cu" "F.Mask" "F.Paste")
			(net "SMB_PCH_MEZZ_LOM1_SCL")
		)
		(pad "27" smd rect
			(at 0 20.80006 90)
			(size 2.0066 0.508)
			(layers "F.Cu" "F.Mask" "F.Paste")
			(net "SMB_PCH_MEZZ_LOM1_SDA")
		)
		(pad "28" smd rect
			(at 0 21.599906 90)
			(size 2.0066 0.508)
			(layers "F.Cu" "F.Mask" "F.Paste")
			(net "GND")
		)
		(pad "29" smd rect
			(at 0 22.400006 90)
			(size 2.0066 0.508)
			(layers "F.Cu" "F.Mask" "F.Paste")
			(net "SMB_PCH_MEZZ_LOM3_SCL")
		)
		(pad "30" smd rect
			(at 0 23.200106 90)
			(size 2.0066 0.508)
			(layers "F.Cu" "F.Mask" "F.Paste")
			(net "SMB_PCH_MEZZ_LOM3_SDA")
		)
		(pad "31" smd rect
			(at 0 23.999952 90)
			(size 2.0066 0.508)
			(layers "F.Cu" "F.Mask" "F.Paste")
			(net "FM_GBE2_LVC3_MOD_ABS")
		)
		(pad "32" smd rect
			(at 0 24.800052 90)
			(size 2.0066 0.508)
			(layers "F.Cu" "F.Mask" "F.Paste")
			(net "FM_GBE3_LVC3_MOD_ABS")
		)
		(pad "33" smd rect
			(at 4.406646 0 90)
			(size 2.0066 0.508)
			(layers "F.Cu" "F.Mask" "F.Paste")
			(net "P12V_STBY")
		)
		(pad "34" smd rect
			(at 4.406646 0.8001 90)
			(size 2.0066 0.508)
			(layers "F.Cu" "F.Mask" "F.Paste")
			(net "P12V_STBY")
		)
		(pad "35" smd rect
			(at 4.406646 1.599946 90)
			(size 2.0066 0.508)
			(layers "F.Cu" "F.Mask" "F.Paste")
			(net "P12V_STBY")
		)
		(pad "36" smd rect
			(at 4.406646 2.400046 90)
			(size 2.0066 0.508)
			(layers "F.Cu" "F.Mask" "F.Paste")
			(net "TP_RSVD<0>")
		)
		(pad "37" smd rect
			(at 4.406646 3.199892 90)
			(size 2.0066 0.508)
			(layers "F.Cu" "F.Mask" "F.Paste")
			(net "FM_GBE0_LVC3_MOD_ABS")
		)
		(pad "38" smd rect
			(at 4.406646 3.999992 90)
			(size 2.0066 0.508)
			(layers "F.Cu" "F.Mask" "F.Paste")
			(net "FM_GBE1_LVC3_MOD_ABS")
		)
		(pad "39" smd rect
			(at 4.406646 4.800092 90)
			(size 2.0066 0.508)
			(layers "F.Cu" "F.Mask" "F.Paste")
			(net "GND")
		)
		(pad "40" smd rect
			(at 4.406646 5.599938 90)
			(size 2.0066 0.508)
			(layers "F.Cu" "F.Mask" "F.Paste")
			(net "KR_P0_OCP_TX_DP")
		)
		(pad "41" smd rect
			(at 4.406646 6.400038 90)
			(size 2.0066 0.508)
			(layers "F.Cu" "F.Mask" "F.Paste")
			(net "KR_P0_OCP_TX_DN")
		)
		(pad "42" smd rect
			(at 4.406646 7.199884 90)
			(size 2.0066 0.508)
			(layers "F.Cu" "F.Mask" "F.Paste")
			(net "GND")
		)
		(pad "43" smd rect
			(at 4.406646 7.999984 90)
			(size 2.0066 0.508)
			(layers "F.Cu" "F.Mask" "F.Paste")
			(net "LED_GBE_P0_0")
		)
		(pad "44" smd rect
			(at 4.406646 8.800084 90)
			(size 2.0066 0.508)
			(layers "F.Cu" "F.Mask" "F.Paste")
			(net "LED_GBE_P0_1")
		)
		(pad "45" smd rect
			(at 4.406646 9.59993 90)
			(size 2.0066 0.508)
			(layers "F.Cu" "F.Mask" "F.Paste")
			(net "GND")
		)
		(pad "46" smd rect
			(at 4.406646 10.40003 90)
			(size 2.0066 0.508)
			(layers "F.Cu" "F.Mask" "F.Paste")
			(net "KR_P1_OCP_TX_DP")
		)
		(pad "47" smd rect
			(at 4.406646 11.199876 90)
			(size 2.0066 0.508)
			(layers "F.Cu" "F.Mask" "F.Paste")
			(net "KR_P1_OCP_TX_DN")
		)
		(pad "48" smd rect
			(at 4.406646 11.999976 90)
			(size 2.0066 0.508)
			(layers "F.Cu" "F.Mask" "F.Paste")
			(net "GND")
		)
		(pad "49" smd rect
			(at 4.406646 12.800076 90)
			(size 2.0066 0.508)
			(layers "F.Cu" "F.Mask" "F.Paste")
			(net "TP_SHARED_KR_MDC_0")
		)
		(pad "50" smd rect
			(at 4.406646 13.599922 90)
			(size 2.0066 0.508)
			(layers "F.Cu" "F.Mask" "F.Paste")
			(net "TP_SHARED_KR_MDIO_0")
		)
		(pad "51" smd rect
			(at 4.406646 14.400022 90)
			(size 2.0066 0.508)
			(layers "F.Cu" "F.Mask" "F.Paste")
			(net "GND")
		)
		(pad "52" smd rect
			(at 4.406646 15.200122 90)
			(size 2.0066 0.508)
			(layers "F.Cu" "F.Mask" "F.Paste")
			(net "KR_P0_OCP_RX_DP")
		)
		(pad "53" smd rect
			(at 4.406646 15.999968 90)
			(size 2.0066 0.508)
			(layers "F.Cu" "F.Mask" "F.Paste")
			(net "KR_P0_OCP_RX_DN")
		)
		(pad "54" smd rect
			(at 4.406646 16.800068 90)
			(size 2.0066 0.508)
			(layers "F.Cu" "F.Mask" "F.Paste")
			(net "GND")
		)
		(pad "55" smd rect
			(at 4.406646 17.599914 90)
			(size 2.0066 0.508)
			(layers "F.Cu" "F.Mask" "F.Paste")
			(net "LED_GBE_P3_0")
		)
		(pad "56" smd rect
			(at 4.406646 18.400014 90)
			(size 2.0066 0.508)
			(layers "F.Cu" "F.Mask" "F.Paste")
			(net "LED_GBE_P3_1")
		)
		(pad "57" smd rect
			(at 4.406646 19.200114 90)
			(size 2.0066 0.508)
			(layers "F.Cu" "F.Mask" "F.Paste")
			(net "GND")
		)
		(pad "58" smd rect
			(at 4.406646 19.99996 90)
			(size 2.0066 0.508)
			(layers "F.Cu" "F.Mask" "F.Paste")
			(net "KR_P1_OCP_RX_DP")
		)
		(pad "59" smd rect
			(at 4.406646 20.80006 90)
			(size 2.0066 0.508)
			(layers "F.Cu" "F.Mask" "F.Paste")
			(net "KR_P1_OCP_RX_DN")
		)
		(pad "60" smd rect
			(at 4.406646 21.599906 90)
			(size 2.0066 0.508)
			(layers "F.Cu" "F.Mask" "F.Paste")
			(net "GND")
		)
		(pad "61" smd rect
			(at 4.406646 22.400006 90)
			(size 2.0066 0.508)
			(layers "F.Cu" "F.Mask" "F.Paste")
			(net "SMB_PCH_MEZZ_LOM2_SCL")
		)
		(pad "62" smd rect
			(at 4.406646 23.200106 90)
			(size 2.0066 0.508)
			(layers "F.Cu" "F.Mask" "F.Paste")
			(net "SMB_PCH_MEZZ_LOM2_SDA")
		)
		(pad "63" smd rect
			(at 4.406646 23.999952 90)
			(size 2.0066 0.508)
			(layers "F.Cu" "F.Mask" "F.Paste")
			(net "GND")
		)
		(pad "64" smd rect
			(at 4.406646 24.800052 90)
			(size 2.0066 0.508)
			(layers "F.Cu" "F.Mask" "F.Paste")
			(net "FM_OCP_MEZZC_PRES_N")
		)
		(zone
			(layers "F.Cu" "B.Cu" "In1.Cu" "In2.Cu" "In3.Cu" "In4.Cu" "In5.Cu" "In6.Cu"
				"In7.Cu" "In8.Cu" "In9.Cu" "In10.Cu" "In11.Cu" "In12.Cu"
			)
			(hatch none 0.5)
			(connect_pads
				(clearance 0)
			)
			(min_thickness 0.25)
			(keepout
				(tracks not_allowed)
				(vias allowed)
				(pads allowed)
				(copperpour not_allowed)
				(footprints allowed)
			)
			(placement
				(enabled no)
				(sheetname "")
			)
			(fill
				(thermal_gap 0.5)
				(thermal_bridge_width 0.5)
				(island_removal_mode 0)
			)
			(polygon
				(pts
					(arc
						(start 468.573866 -59.79922)
						(mid 467.126066 -59.79922)
						(end 468.573866 -59.79922)
					)
				)
			)
		)
		(zone
			(layers "F.Cu" "B.Cu" "In1.Cu" "In2.Cu" "In3.Cu" "In4.Cu" "In5.Cu" "In6.Cu"
				"In7.Cu" "In8.Cu" "In9.Cu" "In10.Cu" "In11.Cu" "In12.Cu"
			)
			(hatch none 0.5)
			(connect_pads
				(clearance 0)
			)
			(min_thickness 0.25)
			(keepout
				(tracks not_allowed)
				(vias allowed)
				(pads allowed)
				(copperpour not_allowed)
				(footprints allowed)
			)
			(placement
				(enabled no)
				(sheetname "")
			)
			(fill
				(thermal_gap 0.5)
				(thermal_bridge_width 0.5)
				(island_removal_mode 0)
			)
			(polygon
				(pts
					(arc
						(start 438.964324 -59.79922)
						(mid 437.135524 -59.79922)
						(end 438.964324 -59.79922)
					)
				)
			)
		)
	)
	(footprint ""
		(layer "F.Cu")
		(at 337.947 -13.97 90)
		(property "Reference" "R7G9"
			(at 0 0 90)
			(layer "F.SilkS")
			(hide yes)
			(effects
				(font
					(size 1.27 1.27)
				)
			)
		)
		(property "Value" ""
			(at 0 0 90)
			(layer "F.Fab")
			(effects
				(font
					(size 1.27 1.27)
				)
			)
		)
		(duplicate_pad_numbers_are_jumpers no)
		(fp_rect
			(start 0.2794 -0.1016)
			(end -0.2794 0.9906)
			(stroke
				(width 0)
				(type default)
			)
			(fill no)
			(layer "F.CrtYd")
		)
		(fp_line
			(start 0.2794 -0.1016)
			(end -0.2794 -0.1016)
			(stroke
				(width 0.1)
				(type default)
			)
			(layer "F.Fab")
		)
		(fp_line
			(start -0.2794 -0.1016)
			(end -0.2794 0.9906)
			(stroke
				(width 0.1)
				(type default)
			)
			(layer "F.Fab")
		)
		(fp_line
			(start 0.2794 0.9906)
			(end 0.2794 -0.1016)
			(stroke
				(width 0.1)
				(type default)
			)
			(layer "F.Fab")
		)
		(fp_line
			(start -0.2794 0.9906)
			(end 0.2794 0.9906)
			(stroke
				(width 0.1)
				(type default)
			)
			(layer "F.Fab")
		)
		(pad "1" smd rect
			(at 0 0 90)
			(size 0.508 0.508)
			(layers "F.Cu" "F.Mask" "F.Paste")
			(net "VSENSE_PVDDQ_ABC_P")
		)
		(pad "2" smd rect
			(at 0 0.889 90)
			(size 0.508 0.508)
			(layers "F.Cu" "F.Mask" "F.Paste")
			(net "VR_PVDDQ_ABC_AVSP")
		)
		(zone
			(layer "F.Cu")
			(hatch none 0.5)
			(connect_pads
				(clearance 0)
			)
			(min_thickness 0.25)
			(keepout
				(tracks not_allowed)
				(vias allowed)
				(pads allowed)
				(copperpour not_allowed)
				(footprints allowed)
			)
			(placement
				(enabled no)
				(sheetname "")
			)
			(fill
				(thermal_gap 0.5)
				(thermal_bridge_width 0.5)
				(island_removal_mode 0)
			)
			(polygon
				(pts
					(xy 338.201 -14.224) (xy 338.201 -13.716) (xy 338.582 -13.716) (xy 338.582 -14.224)
				)
			)
		)
		(zone
			(layer "F.Cu")
			(hatch none 0.5)
			(connect_pads
				(clearance 0)
			)
			(min_thickness 0.25)
			(keepout
				(tracks allowed)
				(vias not_allowed)
				(pads allowed)
				(copperpour not_allowed)
				(footprints allowed)
			)
			(placement
				(enabled no)
				(sheetname "")
			)
			(fill
				(thermal_gap 0.5)
				(thermal_bridge_width 0.5)
				(island_removal_mode 0)
			)
			(polygon
				(pts
					(xy 338.201 -14.224) (xy 338.201 -13.716) (xy 338.582 -13.716) (xy 338.582 -14.224)
				)
			)
		)
	)
)
